(kicad_pcb
	(version 20241229)
	(generator "pcbnew")
	(generator_version "9.0")
	(general
		(thickness 1.62)
		(legacy_teardrops no)
	)
	(paper "A3")
	(title_block
		(title "COM Express 7 Baseboard")
		(date "2025-02-04")
		(rev "1.1.2")
		(company "Antmicro Ltd")
		(comment 1 "www.antmicro.com")
		(comment 9 "footprints 150-153 of 802")
	)
	(layers
		(0 "F.Cu" signal)
		(4 "In1.Cu" signal)
		(6 "In2.Cu" signal)
		(8 "In3.Cu" signal)
		(10 "In4.Cu" signal)
		(12 "In5.Cu" signal)
		(14 "In6.Cu" signal)
		(2 "B.Cu" signal)
		(9 "F.Adhes" user "F.Adhesive")
		(11 "B.Adhes" user "B.Adhesive")
		(13 "F.Paste" user)
		(15 "B.Paste" user)
		(5 "F.SilkS" user "F.Silkscreen")
		(7 "B.SilkS" user "B.Silkscreen")
		(1 "F.Mask" user)
		(3 "B.Mask" user)
		(17 "Dwgs.User" user "User.Drawings")
		(19 "Cmts.User" user "User.Comments")
		(21 "Eco1.User" user "User.Eco1")
		(23 "Eco2.User" user "User.Eco2")
		(25 "Edge.Cuts" user)
		(27 "Margin" user)
		(31 "F.CrtYd" user "F.Courtyard")
		(29 "B.CrtYd" user "B.Courtyard")
		(35 "F.Fab" user)
		(33 "B.Fab" user)
	)
	(footprint "antmicro-footprints:R_0402_1005Metric"
		(layer "F.Cu")
		(at 211.28 126.09)
		(descr "Resistor SMD 0402")
		(tags "resistor SMD 0402")
		(property "Reference" "R178"
			(at -3.68 0.17 0)
			(layer "F.SilkS")
			(effects
				(font
					(size 0.7 0.7)
					(thickness 0.15)
				)
				(justify left bottom)
			)
		)
		(property "Value" "R_0R_0402"
			(at -1.011843 1.772047 0)
			(layer "F.Fab")
			(effects
				(font
					(size 0.7 0.7)
					(thickness 0.15)
				)
				(justify left bottom)
			)
		)
		(property "Datasheet" "https://industrial.panasonic.com/cdbs/www-data/pdf/RDA0000/AOA0000C301.pdf"
			(at 0 0 0)
			(layer "F.Fab")
			(hide yes)
			(effects
				(font
					(size 1.27 1.27)
					(thickness 0.15)
				)
			)
		)
		(property "Author" "Antmicro"
			(at 0 0 0)
			(layer "F.Fab")
			(hide yes)
			(effects
				(font
					(size 1 1)
					(thickness 0.15)
				)
			)
		)
		(property "Current" "1A"
			(at 0 0 0)
			(layer "F.Fab")
			(hide yes)
			(effects
				(font
					(size 1 1)
					(thickness 0.15)
				)
			)
		)
		(property "License" "Apache-2.0"
			(at 0 0 0)
			(layer "F.Fab")
			(hide yes)
			(effects
				(font
					(size 1 1)
					(thickness 0.15)
				)
			)
		)
		(property "MPN" "ERJ2GE0R00X"
			(at 0 0 0)
			(layer "F.Fab")
			(hide yes)
			(effects
				(font
					(size 1 1)
					(thickness 0.15)
				)
			)
		)
		(property "Manufacturer" "Panasonic"
			(at 0 0 0)
			(layer "F.Fab")
			(hide yes)
			(effects
				(font
					(size 1 1)
					(thickness 0.15)
				)
			)
		)
		(property "Public" "False"
			(at 0 0 0)
			(layer "F.Fab")
			(hide yes)
			(effects
				(font
					(size 1 1)
					(thickness 0.15)
				)
			)
		)
		(property "Tolerance" ""
			(at 0 0 0)
			(layer "F.Fab")
			(hide yes)
			(effects
				(font
					(size 1 1)
					(thickness 0.15)
				)
			)
		)
		(property "Val" "0R"
			(at 0 0 0)
			(layer "F.Fab")
			(hide yes)
			(effects
				(font
					(size 1 1)
					(thickness 0.15)
				)
			)
		)
		(sheetname "PCIe misc")
		(sheetfile "pcie_misc.kicad_sch")
		(attr smd dnp)
		(fp_rect
			(start -0.925 -0.47)
			(end 0.925 0.47)
			(stroke
				(width 0.05)
				(type default)
			)
			(fill no)
			(layer "F.CrtYd")
		)
		(fp_rect
			(start -0.5 -0.25)
			(end 0.5 0.25)
			(stroke
				(width 0.15)
				(type solid)
			)
			(fill no)
			(layer "F.Fab")
		)
		(pad "1" smd roundrect
			(at -0.48 0)
			(size 0.59 0.64)
			(layers "F.Cu" "F.Mask" "F.Paste")
			(roundrect_rratio 0.25)
			(net 529 "/M.2 key M #1/~{CLKREQ}")
			(pintype "passive")
			(teardrops
				(best_length_ratio 0.2)
				(max_length 1)
				(best_width_ratio 0.9)
				(max_width 2)
				(curved_edges yes)
				(filter_ratio 0.9)
				(enabled yes)
				(allow_two_segments yes)
				(prefer_zone_connections yes)
			)
		)
		(pad "2" smd roundrect
			(at 0.48 0)
			(size 0.59 0.64)
			(layers "F.Cu" "F.Mask" "F.Paste")
			(roundrect_rratio 0.25)
			(net 602 "Net-(U37-~{OE0})")
			(pintype "passive")
			(teardrops
				(best_length_ratio 0.2)
				(max_length 1)
				(best_width_ratio 0.9)
				(max_width 2)
				(curved_edges yes)
				(filter_ratio 0.9)
				(enabled yes)
				(allow_two_segments yes)
				(prefer_zone_connections yes)
			)
		)
	)
	(footprint "antmicro-footprints:R_0805_2012Metric"
		(layer "F.Cu")
		(at 304.25 135.813 180)
		(property "Reference" "R114"
			(at -1.35 0.953 0)
			(layer "F.SilkS")
			(effects
				(font
					(size 0.7 0.7)
					(thickness 0.15)
				)
				(justify right bottom)
			)
		)
		(property "Value" "R_0R001_0805"
			(at 0 1.8 0)
			(layer "F.Fab")
			(effects
				(font
					(size 0.7 0.7)
					(thickness 0.15)
				)
				(justify right bottom)
			)
		)
		(property "Datasheet" "https://www.eaton.com/content/dam/eaton/products/electronic-components/resources/data-sheet/eaton-msma-automotive-smd-current-sense-resistor-metal-strip-data-sheet-elx1179.pdf"
			(at 0 0 180)
			(layer "F.Fab")
			(hide yes)
			(effects
				(font
					(size 1.27 1.27)
					(thickness 0.15)
				)
			)
		)
		(property "Author" "Antmicro"
			(at 608.5 271.626 0)
			(layer "F.Fab")
			(hide yes)
			(effects
				(font
					(size 1 1)
					(thickness 0.15)
				)
			)
		)
		(property "License" "Apache-2.0"
			(at 608.5 271.626 0)
			(layer "F.Fab")
			(hide yes)
			(effects
				(font
					(size 1 1)
					(thickness 0.15)
				)
			)
		)
		(property "MPN" "MSMA0805R0010FSM"
			(at 608.5 271.626 0)
			(layer "F.Fab")
			(hide yes)
			(effects
				(font
					(size 1 1)
					(thickness 0.15)
				)
			)
		)
		(property "Manufacturer" "Eaton"
			(at 608.5 271.626 0)
			(layer "F.Fab")
			(hide yes)
			(effects
				(font
					(size 1 1)
					(thickness 0.15)
				)
			)
		)
		(property "Public" "False"
			(at 608.5 271.626 0)
			(layer "F.Fab")
			(hide yes)
			(effects
				(font
					(size 1 1)
					(thickness 0.15)
				)
			)
		)
		(property "Tolerance" "1%"
			(at 608.5 271.626 0)
			(layer "F.Fab")
			(hide yes)
			(effects
				(font
					(size 1 1)
					(thickness 0.15)
				)
			)
		)
		(property "Val" "0R001"
			(at 608.5 271.626 0)
			(layer "F.Fab")
			(hide yes)
			(effects
				(font
					(size 1 1)
					(thickness 0.15)
				)
			)
		)
		(sheetname "Power")
		(sheetfile "power.kicad_sch")
		(attr smd)
		(fp_line
			(start -0.3 -0.701)
			(end 0.298 -0.701)
			(stroke
				(width 0.15)
				(type solid)
			)
			(layer "F.SilkS")
		)
		(fp_line
			(start -0.32 0.699)
			(end 0.28 0.699)
			(stroke
				(width 0.15)
				(type solid)
			)
			(layer "F.SilkS")
		)
		(fp_rect
			(start 1.95 -0.9)
			(end -1.95 0.9)
			(stroke
				(width 0.05)
				(type default)
			)
			(fill no)
			(layer "F.CrtYd")
		)
		(fp_line
			(start 0.949 -0.677)
			(end 0.949 0.675)
			(stroke
				(width 0.15)
				(type solid)
			)
			(layer "F.Fab")
		)
		(fp_line
			(start -0.951 0.68)
			(end 0.949 0.68)
			(stroke
				(width 0.15)
				(type solid)
			)
			(layer "F.Fab")
		)
		(fp_line
			(start -0.951 -0.677)
			(end -0.951 0.675)
			(stroke
				(width 0.15)
				(type solid)
			)
			(layer "F.Fab")
		)
		(fp_line
			(start -0.951 -0.682)
			(end 0.949 -0.682)
			(stroke
				(width 0.15)
				(type solid)
			)
			(layer "F.Fab")
		)
		(pad "1" smd roundrect
			(at -1.1 0 180)
			(size 1.2 1.3)
			(layers "F.Cu" "F.Mask" "F.Paste")
			(roundrect_rratio 0.25)
			(net 76 "Net-(C63-Pad2)")
			(pintype "passive")
			(teardrops
				(best_length_ratio 0.2)
				(max_length 1)
				(best_width_ratio 0.9)
				(max_width 2)
				(curved_edges yes)
				(filter_ratio 0.9)
				(enabled yes)
				(allow_two_segments yes)
				(prefer_zone_connections yes)
			)
		)
		(pad "2" smd roundrect
			(at 1.1 0 180)
			(size 1.2 1.3)
			(layers "F.Cu" "F.Mask" "F.Paste")
			(roundrect_rratio 0.25)
			(net 78 "+1V8")
			(pintype "passive")
			(teardrops
				(best_length_ratio 0.2)
				(max_length 1)
				(best_width_ratio 0.9)
				(max_width 2)
				(curved_edges yes)
				(filter_ratio 0.9)
				(enabled yes)
				(allow_two_segments yes)
				(prefer_zone_connections yes)
			)
		)
	)
	(footprint "antmicro-footprints:R_0402_1005Metric"
		(layer "F.Cu")
		(at 142.37 145.05)
		(descr "Resistor SMD 0402")
		(tags "resistor SMD 0402")
		(property "Reference" "R248"
			(at -3.72 1.16 0)
			(layer "F.SilkS")
			(effects
				(font
					(size 0.7 0.7)
					(thickness 0.15)
				)
				(justify left bottom)
			)
		)
		(property "Value" "R_0R_0402"
			(at -1.011843 1.772047 0)
			(layer "F.Fab")
			(effects
				(font
					(size 0.7 0.7)
					(thickness 0.15)
				)
				(justify left bottom)
			)
		)
		(property "Datasheet" "https://industrial.panasonic.com/cdbs/www-data/pdf/RDA0000/AOA0000C301.pdf"
			(at 0 0 0)
			(layer "F.Fab")
			(hide yes)
			(effects
				(font
					(size 1.27 1.27)
					(thickness 0.15)
				)
			)
		)
		(property "Author" "Antmicro"
			(at 0 0 0)
			(layer "F.Fab")
			(hide yes)
			(effects
				(font
					(size 1 1)
					(thickness 0.15)
				)
			)
		)
		(property "Current" "1A"
			(at 0 0 0)
			(layer "F.Fab")
			(hide yes)
			(effects
				(font
					(size 1 1)
					(thickness 0.15)
				)
			)
		)
		(property "License" "Apache-2.0"
			(at 0 0 0)
			(layer "F.Fab")
			(hide yes)
			(effects
				(font
					(size 1 1)
					(thickness 0.15)
				)
			)
		)
		(property "MPN" "ERJ2GE0R00X"
			(at 0 0 0)
			(layer "F.Fab")
			(hide yes)
			(effects
				(font
					(size 1 1)
					(thickness 0.15)
				)
			)
		)
		(property "Manufacturer" "Panasonic"
			(at 0 0 0)
			(layer "F.Fab")
			(hide yes)
			(effects
				(font
					(size 1 1)
					(thickness 0.15)
				)
			)
		)
		(property "Public" "False"
			(at 0 0 0)
			(layer "F.Fab")
			(hide yes)
			(effects
				(font
					(size 1 1)
					(thickness 0.15)
				)
			)
		)
		(property "Tolerance" ""
			(at 0 0 0)
			(layer "F.Fab")
			(hide yes)
			(effects
				(font
					(size 1 1)
					(thickness 0.15)
				)
			)
		)
		(property "Val" "0R"
			(at 0 0 0)
			(layer "F.Fab")
			(hide yes)
			(effects
				(font
					(size 1 1)
					(thickness 0.15)
				)
			)
		)
		(sheetname "KR to SFI #1")
		(sheetfile "kr_sfi.kicad_sch")
		(attr smd)
		(fp_rect
			(start -0.925 -0.47)
			(end 0.925 0.47)
			(stroke
				(width 0.05)
				(type default)
			)
			(fill no)
			(layer "F.CrtYd")
		)
		(fp_rect
			(start -0.5 -0.25)
			(end 0.5 0.25)
			(stroke
				(width 0.15)
				(type solid)
			)
			(fill no)
			(layer "F.Fab")
		)
		(pad "1" smd roundrect
			(at -0.48 0)
			(size 0.59 0.64)
			(layers "F.Cu" "F.Mask" "F.Paste")
			(roundrect_rratio 0.25)
			(net 650 "/2xSFP+/KR to SFI #1/MDC_R")
			(pintype "passive")
			(teardrops
				(best_length_ratio 0.2)
				(max_length 1)
				(best_width_ratio 0.9)
				(max_width 2)
				(curved_edges yes)
				(filter_ratio 0.9)
				(enabled yes)
				(allow_two_segments yes)
				(prefer_zone_connections yes)
			)
		)
		(pad "2" smd roundrect
			(at 0.48 0)
			(size 0.59 0.64)
			(layers "F.Cu" "F.Mask" "F.Paste")
			(roundrect_rratio 0.25)
			(net 651 "/2xSFP+/KR to SFI #1/MDC")
			(pintype "passive")
			(teardrops
				(best_length_ratio 0.2)
				(max_length 1)
				(best_width_ratio 0.9)
				(max_width 2)
				(curved_edges yes)
				(filter_ratio 0.9)
				(enabled yes)
				(allow_two_segments yes)
				(prefer_zone_connections yes)
			)
		)
	)
	(footprint "antmicro-footprints:R_0402_1005Metric"
		(layer "F.Cu")
		(at 221.16 129.65)
		(descr "Resistor SMD 0402")
		(tags "resistor SMD 0402")
		(property "Reference" "R201"
			(at 0.79 0.46 0)
			(layer "F.SilkS")
			(effects
				(font
					(size 0.7 0.7)
					(thickness 0.15)
				)
				(justify left bottom)
			)
		)
		(property "Value" "R_0R_0402"
			(at -1.011843 1.772047 0)
			(layer "F.Fab")
			(effects
				(font
					(size 0.7 0.7)
					(thickness 0.15)
				)
				(justify left bottom)
			)
		)
		(property "Datasheet" "https://industrial.panasonic.com/cdbs/www-data/pdf/RDA0000/AOA0000C301.pdf"
			(at 0 0 0)
			(layer "F.Fab")
			(hide yes)
			(effects
				(font
					(size 1.27 1.27)
					(thickness 0.15)
				)
			)
		)
		(property "Author" "Antmicro"
			(at 0 0 0)
			(layer "F.Fab")
			(hide yes)
			(effects
				(font
					(size 1 1)
					(thickness 0.15)
				)
			)
		)
		(property "Current" "1A"
			(at 0 0 0)
			(layer "F.Fab")
			(hide yes)
			(effects
				(font
					(size 1 1)
					(thickness 0.15)
				)
			)
		)
		(property "License" "Apache-2.0"
			(at 0 0 0)
			(layer "F.Fab")
			(hide yes)
			(effects
				(font
					(size 1 1)
					(thickness 0.15)
				)
			)
		)
		(property "MPN" "ERJ2GE0R00X"
			(at 0 0 0)
			(layer "F.Fab")
			(hide yes)
			(effects
				(font
					(size 1 1)
					(thickness 0.15)
				)
			)
		)
		(property "Manufacturer" "Panasonic"
			(at 0 0 0)
			(layer "F.Fab")
			(hide yes)
			(effects
				(font
					(size 1 1)
					(thickness 0.15)
				)
			)
		)
		(property "Public" "False"
			(at 0 0 0)
			(layer "F.Fab")
			(hide yes)
			(effects
				(font
					(size 1 1)
					(thickness 0.15)
				)
			)
		)
		(property "Tolerance" ""
			(at 0 0 0)
			(layer "F.Fab")
			(hide yes)
			(effects
				(font
					(size 1 1)
					(thickness 0.15)
				)
			)
		)
		(property "Val" "0R"
			(at 0 0 0)
			(layer "F.Fab")
			(hide yes)
			(effects
				(font
					(size 1 1)
					(thickness 0.15)
				)
			)
		)
		(sheetname "PCIe misc")
		(sheetfile "pcie_misc.kicad_sch")
		(attr smd)
		(fp_rect
			(start -0.925 -0.47)
			(end 0.925 0.47)
			(stroke
				(width 0.05)
				(type default)
			)
			(fill no)
			(layer "F.CrtYd")
		)
		(fp_rect
			(start -0.5 -0.25)
			(end 0.5 0.25)
			(stroke
				(width 0.15)
				(type solid)
			)
			(fill no)
			(layer "F.Fab")
		)
		(pad "1" smd roundrect
			(at -0.48 0)
			(size 0.59 0.64)
			(layers "F.Cu" "F.Mask" "F.Paste")
			(roundrect_rratio 0.25)
			(net 620 "/PCIe misc/DIF4-")
			(pintype "passive")
			(teardrops
				(best_length_ratio 0.2)
				(max_length 1)
				(best_width_ratio 0.9)
				(max_width 2)
				(curved_edges yes)
				(filter_ratio 0.9)
				(enabled yes)
				(allow_two_segments yes)
				(prefer_zone_connections yes)
			)
		)
		(pad "2" smd roundrect
			(at 0.48 0)
			(size 0.59 0.64)
			(layers "F.Cu" "F.Mask" "F.Paste")
			(roundrect_rratio 0.25)
			(net 271 "/M.2 key M #2/PCIE_{REF}.CK-")
			(pintype "passive")
			(teardrops
				(best_length_ratio 0.2)
				(max_length 1)
				(best_width_ratio 0.9)
				(max_width 2)
				(curved_edges yes)
				(filter_ratio 0.9)
				(enabled yes)
				(allow_two_segments yes)
				(prefer_zone_connections yes)
			)
		)
	)
)
